# TIMECARD (Time Appliance Project (Time Card)) — schematic netlist excerpt (pin names and nets, part order shuffled) for the footprints in the layout excerpt that follows; sources: Cadence DE-HDL packaged netlist, KiCad conversion of R4006-B0001-02_R01.brd

R29  RESISTOR  100KOHM 1%  pkg SMC_0402R_H016  page 32 : \1\ = XP5R0V_RT ; \2\ = XP5R0V_AGND

(kicad_pcb
	(version 20260206)
	(generator "pcbnew")
	(generator_version "10.0")
	(general
		(thickness 1.6)
		(legacy_teardrops no)
	)
	(paper "A4")
	(title_block
		(title "timecard-production-celestica-r4006 — R4006-B0001-02_R01.brd")
		(comment 1 "Time Appliance Project (Time Card) / footprints 207-207 of 1113")
	)
	(layers
		(0 "F.Cu" signal "TOP")
		(4 "In1.Cu" signal "L02_GND1")
		(6 "In2.Cu" signal "L03_SIG1")
		(8 "In3.Cu" signal "L04_GND2")
		(10 "In4.Cu" signal "L05_VCC1")
		(12 "In5.Cu" signal "L06_VCC2")
		(14 "In6.Cu" signal "L07_GND3")
		(16 "In7.Cu" signal "L08_SIG2")
		(18 "In8.Cu" signal "L09_GND4")
		(2 "B.Cu" signal "BOTTOM")
		(9 "F.Adhes" user "F.Adhesive")
		(11 "B.Adhes" user "B.Adhesive")
		(13 "F.Paste" user "Package Geometry/Pastemask Top")
		(15 "B.Paste" user "Package Geometry/Pastemask Bottom")
		(5 "F.SilkS" user "Ref Des/Silkscreen Top")
		(7 "B.SilkS" user "Ref Des/Silkscreen Bottom")
		(1 "F.Mask" user "Board Geometry/Soldermask Top")
		(3 "B.Mask" user "Board Geometry/Soldermask Bottom")
		(17 "Dwgs.User" user "User.Drawings")
		(19 "Cmts.User" user "User.Comments")
		(21 "Eco1.User" user "User.Eco1")
		(23 "Eco2.User" user "User.Eco2")
		(25 "Edge.Cuts" user "Board Geometry/Outline")
		(27 "Margin" user)
		(31 "F.CrtYd" user "Package Geometry/Place Bound Top")
		(29 "B.CrtYd" user "Package Geometry/Place Bound Bottom")
		(35 "F.Fab" user "Ref Des/Assembly Top")
		(33 "B.Fab" user "Ref Des/Assembly Bottom")
	)
	(footprint ""
		(layer "F.Cu")
		(at 39.5224 -105.1814 90)
		(property "Reference" "R29"
			(at 1.58623 -1.5494 0)
			(unlocked yes)
			(layer "F.SilkS")
			(effects
				(font
					(size 0.7874 0.5842)
					(thickness 0.1524)
				)
			)
		)
		(property "Value" "VAL*"
			(at 0.02032 2.13233 90)
			(unlocked yes)
			(layer "F.Fab")
			(hide yes)
			(effects
				(font
					(size 0.7874 0.5842)
					(thickness 0.1524)
				)
			)
		)
		(property "Device Type" "RESISTOR-G155-11003-01,100KOHMA"
			(at 0.008382 1.210564 90)
			(unlocked yes)
			(layer "F.Fab")
			(hide yes)
			(effects
				(font
					(size 0.7874 0.5842)
					(thickness 0.1524)
				)
			)
		)
		(property "User Part Number" "PARTNUM*"
			(at 0.02032 4.024884 90)
			(unlocked yes)
			(layer "Cmts.User")
			(hide yes)
			(effects
				(font
					(size 0.7874 0.5842)
					(thickness 0.1524)
				)
			)
		)
		(property "Tolerance" "TOL*"
			(at 0.044704 3.05435 90)
			(unlocked yes)
			(layer "Cmts.User")
			(hide yes)
			(effects
				(font
					(size 0.7874 0.5842)
					(thickness 0.1524)
				)
			)
		)
		(duplicate_pad_numbers_are_jumpers no)
		(fp_line
			(start 1.143 -0.5588)
			(end -1.143 -0.5588)
			(stroke
				(width 0.1)
				(type default)
			)
			(layer "F.SilkS")
		)
		(fp_line
			(start -1.143 -0.5588)
			(end -1.143 0.5588)
			(stroke
				(width 0.1)
				(type default)
			)
			(layer "F.SilkS")
		)
		(fp_line
			(start 1.143 0.5588)
			(end 1.143 -0.5588)
			(stroke
				(width 0.1)
				(type default)
			)
			(layer "F.SilkS")
		)
		(fp_line
			(start -1.143 0.5588)
			(end 1.143 0.5588)
			(stroke
				(width 0.1)
				(type default)
			)
			(layer "F.SilkS")
		)
		(fp_rect
			(start 1.143 0.5588)
			(end -1.143 -0.5588)
			(stroke
				(width 0)
				(type default)
			)
			(fill no)
			(layer "F.CrtYd")
		)
		(fp_line
			(start 0.508 -0.3048)
			(end -0.508 -0.3048)
			(stroke
				(width 0.1)
				(type default)
			)
			(layer "F.Fab")
		)
		(fp_line
			(start -0.508 -0.3048)
			(end -0.508 0.3048)
			(stroke
				(width 0.1)
				(type default)
			)
			(layer "F.Fab")
		)
		(fp_line
			(start 0.508 0.3048)
			(end 0.508 -0.3048)
			(stroke
				(width 0.1)
				(type default)
			)
			(layer "F.Fab")
		)
		(fp_line
			(start -0.508 0.3048)
			(end 0.508 0.3048)
			(stroke
				(width 0.1)
				(type default)
			)
			(layer "F.Fab")
		)
		(pad "1" smd rect
			(at -0.5334 0 90)
			(size 0.7112 0.6096)
			(layers "F.Cu" "F.Mask" "F.Paste")
			(net "XP5R0V_RT")
		)
		(pad "2" smd rect
			(at 0.5334 0 90)
			(size 0.7112 0.6096)
			(layers "F.Cu" "F.Mask" "F.Paste")
			(net "XP5R0V_AGND")
		)
		(zone
			(layer "F.Cu")
			(hatch none 0.5)
			(connect_pads
				(clearance 0)
			)
			(min_thickness 0.25)
			(keepout
				(tracks allowed)
				(vias not_allowed)
				(pads allowed)
				(copperpour not_allowed)
				(footprints allowed)
			)
			(placement
				(enabled no)
				(sheetname "")
			)
			(fill
				(thermal_gap 0.5)
				(thermal_bridge_width 0.5)
				(island_removal_mode 0)
			)
			(polygon
				(pts
					(xy 39.8272 -105.2576) (xy 39.2176 -105.2576) (xy 39.2176 -105.1052) (xy 39.8272 -105.1052)
				)
			)
		)
	)
)
